# T6G (Grand Teton) — schematic netlist excerpt (pin names and nets, part order shuffled) for the footprints in the layout excerpt that follows; sources: Cadence DE-HDL packaged netlist, KiCad conversion of 04192023_DAF0TMB3IC0_F0TG_MB_C_brd_V02_OCP.brd

PC595_2  Q_CAP  22UF 16V 20% X6S  pkg C0805  page 198 : A = SW_P12V_AUX_PVDDCR_SOC_P0_FLT ; B = GND
PR6809  Q_RES  0 5% CHIP  pkg 0402LF  page 364 : A = P12V_AUX ; B = P0V9_RETIMER_CPU1_VINSEN
R1225  Q_RES  18K 1% CHIP  pkg 0402LF  page 258 : A = PVDD18_S5_P1_ADC ; B = GND

(kicad_pcb
	(version 20260206)
	(generator "pcbnew")
	(generator_version "10.0")
	(general
		(thickness 1.6)
		(legacy_teardrops no)
	)
	(paper "A4")
	(title_block
		(title "04192023_DAF0TMB3IC0_F0TG_MB_C_brd_V02_OCP.brd")
		(comment 1 "Grand Teton / footprints 8294-8296 of 8354")
	)
	(layers
		(0 "F.Cu" signal "TOP")
		(4 "In1.Cu" signal "GND")
		(6 "In2.Cu" signal "IN1")
		(8 "In3.Cu" signal "GND1")
		(10 "In4.Cu" signal "IN2")
		(12 "In5.Cu" signal "GND2")
		(14 "In6.Cu" signal "IN3")
		(16 "In7.Cu" signal "GND3")
		(18 "In8.Cu" signal "VCC")
		(20 "In9.Cu" signal "VCC1")
		(22 "In10.Cu" signal "GND4")
		(24 "In11.Cu" signal "IN4")
		(26 "In12.Cu" signal "GND5")
		(28 "In13.Cu" signal "IN5")
		(30 "In14.Cu" signal "GND6")
		(32 "In15.Cu" signal "IN6")
		(34 "In16.Cu" signal "GND7")
		(2 "B.Cu" signal "BOTTOM")
		(9 "F.Adhes" user "F.Adhesive")
		(11 "B.Adhes" user "B.Adhesive")
		(13 "F.Paste" user "Package Geometry/Pastemask Top")
		(15 "B.Paste" user "Package Geometry/Pastemask Bottom")
		(5 "F.SilkS" user "Ref Des/Silkscreen Top")
		(7 "B.SilkS" user "Ref Des/Silkscreen Bottom")
		(1 "F.Mask" user "Board Geometry/Soldermask Top")
		(3 "B.Mask" user "Board Geometry/Soldermask Bottom")
		(17 "Dwgs.User" user "User.Drawings")
		(19 "Cmts.User" user "User.Comments")
		(21 "Eco1.User" user "User.Eco1")
		(23 "Eco2.User" user "User.Eco2")
		(25 "Edge.Cuts" user "Board Geometry/Outline")
		(27 "Margin" user)
		(31 "F.CrtYd" user "Package Geometry/Place Bound Top")
		(29 "B.CrtYd" user "Package Geometry/Place Bound Bottom")
		(35 "F.Fab" user "Ref Des/Assembly Top")
		(33 "B.Fab" user "Ref Des/Assembly Bottom")
	)
	(footprint ""
		(layer "B.Cu")
		(at 401.337018 -168.721532 -90)
		(property "Reference" "PC595_2"
			(at 0 0 90)
			(layer "B.SilkS")
			(hide yes)
			(effects
				(font
					(size 1.27 1.27)
				)
				(justify mirror)
			)
		)
		(property "Value" ""
			(at 0 0 90)
			(layer "B.Fab")
			(effects
				(font
					(size 1.27 1.27)
				)
				(justify mirror)
			)
		)
		(duplicate_pad_numbers_are_jumpers no)
		(fp_line
			(start -1.524 0.762)
			(end 1.524 0.762)
			(stroke
				(width 0.1524)
				(type default)
			)
			(layer "B.SilkS")
		)
		(fp_line
			(start 1.524 0.762)
			(end 1.524 -0.762)
			(stroke
				(width 0.1524)
				(type default)
			)
			(layer "B.SilkS")
		)
		(fp_line
			(start -1.524 -0.762)
			(end -1.524 0.762)
			(stroke
				(width 0.1524)
				(type default)
			)
			(layer "B.SilkS")
		)
		(fp_line
			(start 1.524 -0.762)
			(end -1.524 -0.762)
			(stroke
				(width 0.1524)
				(type default)
			)
			(layer "B.SilkS")
		)
		(fp_line
			(start -1.1049 0.724916)
			(end -1.1049 -0.724916)
			(stroke
				(width 0.1)
				(type default)
			)
			(layer "B.Fab")
		)
		(fp_line
			(start 1.1049 0.724916)
			(end -1.1049 0.724916)
			(stroke
				(width 0.1)
				(type default)
			)
			(layer "B.Fab")
		)
		(fp_line
			(start -1.1049 -0.724916)
			(end 1.1049 -0.724916)
			(stroke
				(width 0.1)
				(type default)
			)
			(layer "B.Fab")
		)
		(fp_line
			(start 1.1049 -0.724916)
			(end 1.1049 0.724916)
			(stroke
				(width 0.1)
				(type default)
			)
			(layer "B.Fab")
		)
		(pad "1" smd rect
			(at 0.889 0 270)
			(size 1.016 1.27)
			(layers "B.Cu" "B.Mask" "B.Paste")
			(net "SW_P12V_AUX_PVDDCR_SOC_P0_FLT")
		)
		(pad "2" smd rect
			(at -0.889 0 270)
			(size 1.016 1.27)
			(layers "B.Cu" "B.Mask" "B.Paste")
			(net "GND")
		)
	)
	(footprint ""
		(layer "B.Cu")
		(at 10.066782 -406.119584 180)
		(property "Reference" "PR6809"
			(at 0 0 0)
			(layer "B.SilkS")
			(hide yes)
			(effects
				(font
					(size 1.27 1.27)
				)
				(justify mirror)
			)
		)
		(property "Value" ""
			(at 0 0 0)
			(layer "B.Fab")
			(effects
				(font
					(size 1.27 1.27)
				)
				(justify mirror)
			)
		)
		(duplicate_pad_numbers_are_jumpers no)
		(fp_line
			(start 0.7874 0.4064)
			(end 0.7874 -0.4064)
			(stroke
				(width 0.1524)
				(type default)
			)
			(layer "B.SilkS")
		)
		(fp_line
			(start 0.7874 -0.4064)
			(end -0.7874 -0.4064)
			(stroke
				(width 0.1524)
				(type default)
			)
			(layer "B.SilkS")
		)
		(fp_line
			(start -0.7874 0.4064)
			(end 0.7874 0.4064)
			(stroke
				(width 0.1524)
				(type default)
			)
			(layer "B.SilkS")
		)
		(fp_line
			(start -0.7874 -0.4064)
			(end -0.7874 0.4064)
			(stroke
				(width 0.1524)
				(type default)
			)
			(layer "B.SilkS")
		)
		(fp_line
			(start 0.67945 0.3048)
			(end 0.67945 -0.305054)
			(stroke
				(width 0.1)
				(type default)
			)
			(layer "B.Fab")
		)
		(fp_line
			(start 0.67945 -0.305054)
			(end 0.12065 -0.305054)
			(stroke
				(width 0.1)
				(type default)
			)
			(layer "B.Fab")
		)
		(fp_line
			(start 0.12065 0.3048)
			(end 0.67945 0.3048)
			(stroke
				(width 0.1)
				(type default)
			)
			(layer "B.Fab")
		)
		(fp_line
			(start 0.12065 0.2794)
			(end 0.12065 0.3048)
			(stroke
				(width 0.1)
				(type default)
			)
			(layer "B.Fab")
		)
		(fp_line
			(start 0.12065 -0.2794)
			(end -0.12065 -0.2794)
			(stroke
				(width 0.1)
				(type default)
			)
			(layer "B.Fab")
		)
		(fp_line
			(start 0.12065 -0.305054)
			(end 0.12065 -0.2794)
			(stroke
				(width 0.1)
				(type default)
			)
			(layer "B.Fab")
		)
		(fp_line
			(start -0.120396 0.3048)
			(end -0.120396 0.2794)
			(stroke
				(width 0.1)
				(type default)
			)
			(layer "B.Fab")
		)
		(fp_line
			(start -0.120396 0.2794)
			(end 0.12065 0.2794)
			(stroke
				(width 0.1)
				(type default)
			)
			(layer "B.Fab")
		)
		(fp_line
			(start -0.12065 -0.2794)
			(end -0.12065 -0.3048)
			(stroke
				(width 0.1)
				(type default)
			)
			(layer "B.Fab")
		)
		(fp_line
			(start -0.12065 -0.3048)
			(end -0.67945 -0.3048)
			(stroke
				(width 0.1)
				(type default)
			)
			(layer "B.Fab")
		)
		(fp_line
			(start -0.67945 0.3048)
			(end -0.120396 0.3048)
			(stroke
				(width 0.1)
				(type default)
			)
			(layer "B.Fab")
		)
		(fp_line
			(start -0.67945 -0.3048)
			(end -0.67945 0.3048)
			(stroke
				(width 0.1)
				(type default)
			)
			(layer "B.Fab")
		)
		(pad "1" smd circle
			(at 0.40005 0)
			(size 0 0)
			(layers "B.Cu" "B.Mask" "B.Paste")
			(net "P12V_AUX")
		)
		(pad "2" smd circle
			(at -0.40005 0)
			(size 0 0)
			(layers "B.Cu" "B.Mask" "B.Paste")
			(net "P0V9_RETIMER_CPU1_VINSEN")
		)
	)
	(footprint ""
		(layer "B.Cu")
		(at 234.844844 -329.173078 180)
		(property "Reference" "R1225"
			(at 0 0 0)
			(layer "B.SilkS")
			(hide yes)
			(effects
				(font
					(size 1.27 1.27)
				)
				(justify mirror)
			)
		)
		(property "Value" ""
			(at 0 0 0)
			(layer "B.Fab")
			(effects
				(font
					(size 1.27 1.27)
				)
				(justify mirror)
			)
		)
		(duplicate_pad_numbers_are_jumpers no)
		(fp_line
			(start 0.7874 0.4064)
			(end 0.7874 -0.4064)
			(stroke
				(width 0.1524)
				(type default)
			)
			(layer "B.SilkS")
		)
		(fp_line
			(start 0.7874 -0.4064)
			(end -0.7874 -0.4064)
			(stroke
				(width 0.1524)
				(type default)
			)
			(layer "B.SilkS")
		)
		(fp_line
			(start -0.7874 0.4064)
			(end 0.7874 0.4064)
			(stroke
				(width 0.1524)
				(type default)
			)
			(layer "B.SilkS")
		)
		(fp_line
			(start -0.7874 -0.4064)
			(end -0.7874 0.4064)
			(stroke
				(width 0.1524)
				(type default)
			)
			(layer "B.SilkS")
		)
		(fp_line
			(start 0.67945 0.3048)
			(end 0.67945 -0.305054)
			(stroke
				(width 0.1)
				(type default)
			)
			(layer "B.Fab")
		)
		(fp_line
			(start 0.67945 -0.305054)
			(end 0.12065 -0.305054)
			(stroke
				(width 0.1)
				(type default)
			)
			(layer "B.Fab")
		)
		(fp_line
			(start 0.12065 0.3048)
			(end 0.67945 0.3048)
			(stroke
				(width 0.1)
				(type default)
			)
			(layer "B.Fab")
		)
		(fp_line
			(start 0.12065 0.2794)
			(end 0.12065 0.3048)
			(stroke
				(width 0.1)
				(type default)
			)
			(layer "B.Fab")
		)
		(fp_line
			(start 0.12065 -0.2794)
			(end -0.12065 -0.2794)
			(stroke
				(width 0.1)
				(type default)
			)
			(layer "B.Fab")
		)
		(fp_line
			(start 0.12065 -0.305054)
			(end 0.12065 -0.2794)
			(stroke
				(width 0.1)
				(type default)
			)
			(layer "B.Fab")
		)
		(fp_line
			(start -0.120396 0.3048)
			(end -0.120396 0.2794)
			(stroke
				(width 0.1)
				(type default)
			)
			(layer "B.Fab")
		)
		(fp_line
			(start -0.120396 0.2794)
			(end 0.12065 0.2794)
			(stroke
				(width 0.1)
				(type default)
			)
			(layer "B.Fab")
		)
		(fp_line
			(start -0.12065 -0.2794)
			(end -0.12065 -0.3048)
			(stroke
				(width 0.1)
				(type default)
			)
			(layer "B.Fab")
		)
		(fp_line
			(start -0.12065 -0.3048)
			(end -0.67945 -0.3048)
			(stroke
				(width 0.1)
				(type default)
			)
			(layer "B.Fab")
		)
		(fp_line
			(start -0.67945 0.3048)
			(end -0.120396 0.3048)
			(stroke
				(width 0.1)
				(type default)
			)
			(layer "B.Fab")
		)
		(fp_line
			(start -0.67945 -0.3048)
			(end -0.67945 0.3048)
			(stroke
				(width 0.1)
				(type default)
			)
			(layer "B.Fab")
		)
		(pad "1" smd circle
			(at 0.40005 0)
			(size 0 0)
			(layers "B.Cu" "B.Mask" "B.Paste")
			(net "PVDD18_S5_P1_ADC")
		)
		(pad "2" smd circle
			(at -0.40005 0)
			(size 0 0)
			(layers "B.Cu" "B.Mask" "B.Paste")
			(net "GND")
		)
	)
)
